# Primary and Alternate BOM of B91.01110.0037_IOM M.2.xls — Sheet0 (bom)
| Part Number | B91.01110.0037 |  |  |  |  |  |  |  |  |  |  |  |  |
| Revision | C |  |  |  |  |  |  |  |  |  |  |  |  |
| Sequence | 1 |  |  |  |  |  |  |  |  |  |  |  |  |
| Description | BRYCE CANYON IOM M.2 PD P-2 MAIN |  |  |  |  |  |  |  |  |  |  |  |  |
| Project Code | BPD011010001 |  |  |  |  |  |  |  |  |  |  |  |  |
| Latest Revision? | YES |  |  |  |  |  |  |  |  |  |  |  |  |
| PDM BOM List |  |  |  |  |  |  |  |  |  |  |  |  |  |
| Level | Parent Number | Part Number | Description | Green Factor | Manufacturer | Manufacturer Part Number | Source | BOM Usage | M/P Code | S/D | Qty | UoM | Location |
| 1 | B91.01110.0037 | B55.01107.0010 | BRYCE CANYON IOM M.2 PD P-2 MAIN(D) | R2; |  |  |  | M | Manufacture |  | 1 | PCS |  |
| 2 | B55.01107.0010 | 020.80818.0001 | CONN SIGNAL XCEDE JX410-50824_REVA | R2_SA; | AMPHENOL | JX410-50824_RevA | Single |  | Purchase | DIP | 1 | PCS | CN1 |
| 2 | B55.01107.0010 | 022.10005.06S1 | SKT USB 3.0 9P GSB31D13001HHR, PA10T | R2_SA;HF_SA; | AMPHENOL | GSB31D13001HHR | Single |  | Purchase | DIP | 1 | PCS | USB1 |
| 2 | B55.01107.0010 | 022.40001.0311 | SW TACT 4P DTSA-65R-Q,PA66/PA6T | R2_SA;HF_SA; | DIPTRONICS | DTSA-65R-Q | Single |  | Purchase | DIP | 1 | PCS | PWR1 |
| 2 | B55.01107.0010 | 022.40001.0A71 | SW TACT 4P DTSA-63K-Q-T/R(566)(766),PA9T | R2_SA;HF_SA; | DIPTRONICS | DTSA-63K-Q-T/R(566)(766) | Single |  | Purchase | DIP | 1 | PCS | RST1 |
| 2 | B55.01107.0010 | 06.WP130.14A | LED BLUE/YELLOW WP130WDT-TD88 3P DIP | R2_SA;HF_SA; | KINGBRIGHT | WP130WDT-TD88 | Single |  | Purchase | DIP | 1 | PCS | LED3 |
| 2 | B55.01107.0010 | 40.58D03.001 | LBL POLYIMIDE31.8*6.35 BARCODE | R2_SA;HF_SA;G_SA; | LABELJET | 40.58D03.001 | Single |  | Purchase | DIP | 1 | PCS |  |
| 2 | B55.01107.0010 | 40.6E727.001 | LBL 50X15MM BLANK WHITE POLYESTER | R2_SA;HF_SA; | WISTRON | 40.6E727.001 | Single |  | Purchase | DIP | 1 | PCS |  |
| 2 | B55.01107.0010 | 640.00X01.0001 | LBL 7X7MM  FOR SONIC | R2_SA;HF_SA; | WISTRON | 640.00X01.0001 | Single |  | Purchase | DIP | 1 | PCS |  |
| 2 | B55.01107.0010 | B42.0110B.0001 | SPACE SUPPORT BRCA KY | R2_SA;HF_SA; | KANGYANG | MSPJ-5V0 | Single |  | Purchase | DIP | 2 | PCS |  |
| 2 | B55.01107.0010 | B42.0111K.1001 | CVR XCEDE SIGNAL JX410-50824 MP | R2_SA;HF_SA; | KANGYANG | COVER-16 | Multiple |  | Purchase | DIP | 1 | PCS |  |
| A(Alternative to previous component) | B55.01107.0010 | B42.0111K.0001 | CVR XCEDE SIGNAL JX410-50824 | R2_SA;HF_SA; | KANGYANG | COVER-16 |  |  | Purchase |  |  |  |  |
| 2 | B55.01107.0010 | B42.01201.1011 | LATCH M.2 H3.9 FIVETECH 2 | R2_SA;HF_SA; | FIVETECH | B42.01201.1011 | Single |  | Purchase | DIP | 2 | PCS |  |
| 2 | B55.01107.0010 | B55.01107.M010 | BRYCE CANYON IOM M.2 PD P-2 MAIN(S) | R2; |  |  |  | M | Manufacture | DIP | 1 | PCS |  |
| 3 | B55.01107.M010 | 020.C0085.0075 | CONN MINI PCI-E 75P MDT580M01001 | R2_SA;HF_SA; | AMPHENOL | MDT580M01001 | Single |  | Purchase | SMT | 2 | PCS | M1 M2 |
| 3 | B55.01107.M010 | 020.F0528.0011 | CONN CTR 11P 91931-31111LF SMD | R2_SA;HF_SA; | FCI | 91931-31111LF | Single |  | Purchase | SMT | 1 | PCS | TPM1 |
| 3 | B55.01107.M010 | 064.18025.06DL | CHIP RES 18K F 1/16W 0402 | R2_SA;HF_SA;G_SA; | KOA;YAGEO | RK73H1ETQTP1802F;RC0402FR-0718KL | Multiple |  | Purchase | SMT | 1 | PCS | R367 |
| 3 | B55.01107.M010 | 064.20515.06DP | CHIP RES 2.05K F 1/16W 0402 | R2_SA;HF_SA;G_SA; | TAI;RALEC;YAGEO | RM04FTN2051;RTT022051FTH;RC0402FR-072K05L | Multiple |  | Purchase | SMT | 1 | PCS | R537 |
| 3 | B55.01107.M010 | 064.41215.06DS | CHIP RES 4.12K F 1/16W 0402 | R2_SA;HF_SA;G_SA; | YAGEO;WALSIN;KOA | RC0402FR-074K12L;WR04X4121FTL;RK73H1ETQTP4121F | Multiple |  | Purchase | SMT | 1 | PCS | R447 |
| 3 | B55.01107.M010 | 064.51015.06DS | CHIP RES 5.1K F 1/16W 0402 | R2_SA;HF_SA;G_SA; | YAGEO;WALSIN;KOA | RC0402FR-075K1L;WR04X5101FTL;RK73H1ETQTP5101F | Multiple |  | Purchase | SMT | 1 | PCS | R448 |
| 3 | B55.01107.M010 | 068.3R310.2091 | CHIP CHOKE 3.3U M PCMB053T-3R3MS | R2_SA;HF_SA; | CYNTEC | PCMB053T-3R3MS | Multiple |  | Purchase | SMT | 1 | PCS | L10 |
| A | B55.01107.M010 | 68.3R31C.10V | CHIP IND 3.3UH MMD-05CZ-3R3M-X2W | R2_SA;HF_SA; | MAGLAYER | MMD-05CZ-3R3M-X2W |  |  | Purchase |  |  |  |  |
| 3 | B55.01107.M010 | 071.02500.M002 | IC VGA AST2500A2-GP 19X19 TFBGA 456P | R2_SA;HF_SA; | ASPEED | AST2500A2-GP | Single |  | Purchase | SMT | 1 | PCS | U2 |
| 3 | B55.01107.M010 | 071.09306.0A0I | IC SMBUS/I2C PCA9306DCTR SSOP8 | R2_SA;HF_SA; | TI | PCA9306DCTR | Multiple |  | Purchase | SMT | 3 | PCS | U45 U82 U83 |
| A | B55.01107.M010 | 71.09306.00W | IC SMBUS/I2C PCA9306DP1 TSSOP 8P | R2_SA;HF_SA; | NXP | PCA9306DP1,125 |  |  | Purchase |  |  |  |  |
| 3 | B55.01107.M010 | 071.09555.000W | IC I/O EXPANDER TCA9555PWR TSSOP 24P | R2_SA;HF_SA; | TI | TCA9555PWR | Multiple |  | Purchase | SMT | 1 | PCS | U34 |
| A | B55.01107.M010 | 71.09555.B0W | IC IO PCA9555PWRG4 TSSOP 24P | R2_SA;HF_SA; | TI | PCA9555PWRG4 |  |  | Purchase |  |  |  |  |
| 3 | B55.01107.M010 | 072.40256.0A0U | IC SDRAM DDR4-2400 256M*16 MT40A256M16GE | R2_SA;HF_SA; | MICRON | MT40A256M16GE-083E:B | Multiple |  | Purchase | SMT | 1 | PCS | U28 |
| A | B55.01107.M010 | 072.44165.0B0U | IC SDRAM K4A4G165WE-BCRC FBGA96P DDR4 | R2_SA;HF_SA; | SAMSUNG | K4A4G165WE-BCRC |  |  | Purchase |  |  |  |  |
| 3 | B55.01107.M010 | 073.03166.000B | IC ANALOG SWITCH NX3L1G66GW,125 TSSOP5 | R2_SA;HF_SA; | NXP | NX3L1G66GW,125 | Multiple |  | Purchase | SMT | 3 | PCS | U12 U15 U16 |
| A | B55.01107.M010 | 073.53166.0A0G | IC ANALOG SWITCH TS5A3166DCKR SC70 | R2_SA;HF_SA; | TI | TS5A3166DCKR |  |  | Purchase |  |  |  |  |
| 3 | B55.01107.M010 | 073.23157.0009 | IC A.S TS5A23157DGSR DGS 10P | R2_SA;HF_SA; | TI | TS5A23157DGSR | Multiple |  | Purchase | SMT | 1 | PCS | U33 |
| A | B55.01107.M010 | 073.52315.0009 | IC A.S TS5A23157TDGSRQ1 MSOP 10P | R2_SA;HF_SA; | TI | TS5A23157TDGSRQ1 |  |  | Purchase |  |  |  |  |
| A | B55.01107.M010 | 073.73157.0009 | IC A.S U7SB3157G-SM2-R MSOP 10P | R2_SA;HF_SA; | UTC | U7SB3157G-SM2-R |  |  | Purchase |  |  |  |  |
| 3 | B55.01107.M010 | 074.01278.0A7Z | IC SWAP CTRL ADM1278-2ACPZ-RL LFCSP 32P | R2_SA;HF_SA; | ADI | ADM1278-2ACPZ-RL | Single |  | Purchase | SMT | 1 | PCS | U35 |
| 3 | B55.01107.M010 | 075.00639.007C | IC FET MOS SSM6P39TU 6P, UF6 | R2_SA;HF_SA; | TOSHIBA | SSM6P39TU | Multiple |  | Purchase | SMT | 1 | PCS | Q27 |
| A | B55.01107.M010 | 84.06P39.03F | FET MOS SSM6P39TU PC UF6 | R2_SA;HF_SA; | TOSHIBA | SSM6P39TU |  |  | Purchase |  |  |  |  |
| 3 | B55.01107.M010 | 077.51571.0001 | CHIP CAP EL POLY 150U 6.3V M7343 ESR17 | R2_SA;HF_SA; | PANASONIC | EEJRX0J151R | Multiple |  | Purchase | SMT | 1 | PCS | C175 |
| A | B55.01107.M010 | 077.C1571.0011 | CHIP CAP POLY T 150U 6.3V M7343 ESR18 | R2_SA;HF_SA; | NECTOKIN | PSKV0J157M018C |  |  | Purchase |  |  |  |  |
| A | B55.01107.M010 | 77.C1571.16L | CHIP CAP POLY T 150U 6.3V M7343 | R2_SA;HF_SA; | PANASONIC | EEFSX0J151ER |  |  | Purchase |  |  |  |  |
| 3 | B55.01107.M010 | 078.1022S.022L | CHIP CAP C 1000P 2KV K1206 X7R | R2_SA;HF_SA; | MURATA;YAGEO | GR431BR7LA102KW66L;CC1206KKX7RDBB102 | Multiple |  | Purchase | SMT | 3 | PCS | C525 C528 C529 |
| 3 | B55.01107.M010 | 078.10521.08F1 | CHIP CAP C 1UF 16V K 0402 X6S | R2_SA;HF_SA;G_SA; | MURATA;DARFON;YAGEO;TAIYO | GRM155C81C105KE11D;C1005X6S105KET;CC0402KRX6S7BB105;LMK105C6105KV-F | Multiple |  | Purchase | SMT | 6 | PCS | C10 C11 C12 C35 C524 C9 |
| 3 | B55.01107.M010 | 078.10620.08B1 | CHIP CAP C 10U 6.3V K0603 X6S | R2_SA;HF_SA; | MURATA | GRM188C80J106KA73D | Multiple |  | Purchase | SMT | 2 | PCS | C104 C115 |
| A | B55.01107.M010 | 078.10610.08B1 | CHIP CAP C 10UF 6.3V M 0603 X6S | R2_SA;HF_SA; | MURATA;SAMSUNG;DARFON;YAGEO;TAIYO | GRM188C80J106MA73D;CL10X106MQ8NNNC;C1608X6S106MCT;CC0603MRX6S5BB106;JMK107BC6106MA-T |  |  | Purchase |  |  |  |  |
| 3 | B55.01107.M010 | 078.10621.0211 | CHIP CAP C 10UF 16V K0805 X7R | R2_SA;HF_SA;G_SA; | SAMSUNG;YAGEO | CL21B106KOQNNNE;CC0805KKX7R7BB106 | Multiple |  | Purchase | SMT | 23 | PCS | C151 C152 C153 C154 C155 C164 C165 C166 C170 C171 C173 C176 C177 C204 C205 C511 C512 C635 C636 C637 C638 C671 C672 |
| 3 | B55.01107.M010 | 078.47522.0211 | CHIP CAP C 4.7U 25V K0805 X7R | R2_SA;HF_SA;G_SA; | DARFON;MURATA;SAMSUNG;TAIYO;WALSIN;YAGEO | C2012X7R475KFP;GRM21BR71E475KA73L;CL21B475KAFNNNE;TMK212AB7475KG-T;0805B475K250CT;CC0805KKX7R8BB475 | Multiple |  | Purchase | SMT | 8 | PCS | C106 C116 C157 C179 C63 C647 C81 C89 |
| 3 | B55.01107.M010 | 082.20005.0001 | OSC 24MHZ 25PPM 15PF HSO321S SMD | R2_SA;HF_SA; | HARMONY | SSW024000E3CH-SR5 | Multiple |  | Purchase | SMT | 1 | PCS | OSC1 |
| A | B55.01107.M010 | 082.20005.0091 | OSC 24MHZ 15P 25PPM HXO-SC SMD | R2_SA;HF_SA; | HOSONIC | D3SX24E000005E |  |  | Purchase |  |  |  |  |
| 3 | B55.01107.M010 | 083.5V0X1.00AF | DIODE ESD PESD5V0X1UAB,115 SOD523 | R2_SA;HF_SA; | NEXPERIA | PESD5V0X1UAB,115 | Single |  | Purchase | SMT | 2 | PCS | D2 D3 |
| 3 | B55.01107.M010 | 084.00925.003N | FET MOS PH0925CL,115 NC LFPAK 4P | R2_SA;HF_SA; | NXP | PH0925CL,115 | Multiple |  | Purchase | SMT | 1 | PCS | Q5 |
| A | B55.01107.M010 | 084.08201.0037 | FET MOS IRFH8201TRPBF PQFN 5X6 8P | R2_SA;HF_SA; | IR | IRFH8201TRPBF |  |  | Purchase |  |  |  |  |
| 3 | B55.01107.M010 | 087.71242.0465 | NUT TPM M3*0.5*L6 NI EVT | R2_SA;HF_SA; | EMI STOP | 087.71242.0465 | Single |  | Purchase | SMT | 1 | PCS | NUT1 |
| 3 | B55.01107.M010 | 20.F1354.120 | CONN CTR SMD 120P 61082-121402LF ,LCP | R2_SA;HF_SA; | FCI | 61082-121402LF | Multiple |  | Purchase | SMT | 1 | PCS | MEZZ1 |
| A | B55.01107.M010 | 020.F0249.0120 | CONN CTR 120P 5177985-5 SMD ,LCP | R2_SA;HF_SA; | TE | 5177985-5 |  |  | Purchase |  |  |  |  |
| 3 | B55.01107.M010 | 62.10089.021 | SKT SPI CONN ACA-SPI-006-K01 ,LCP | R2_SA;HF_SA; | LOTES | ACA-SPI-006-K01 | Single |  | Purchase | SMT | 2 | PCS | SKT1 SKT2 |
| 3 | B55.01107.M010 | 63.10234.1DL | CHIP RES 1K J 1/16W 0402 | R2_SA;HF_SA;G_SA; | TA-I;RALEC;CYNTEC;YAGEO;WALSIN | RM04JTN102 ; RTT02102JTH ; RR0510S-102-JN ; RC0402JR-071KL;WR04X102JTL | Multiple |  | Purchase | SMT | 1 | PCS | R449 |
| 3 | B55.01107.M010 | 63.10334.1DL | CHIP RES 10K J 1/16W 0402 | R2_SA;HF_SA;G_SA; | CYNTEC;RALEC;TA-I;WALSIN;YAGEO | RR0510S-103-JN;RTT02103JTH;RM04JTN103;WR04X103JTL;RC0402JR-0710KL | Multiple |  | Purchase | SMT | 1 | PCS | R722 |
| 3 | B55.01107.M010 | 63.10434.L1L | CHIP RES 100K J 1/16W 0402 13" REEL | R2_SA;HF_SA;G_SA; | YAGEO;RALEC;WALSIN;TAI | RC0402JR-13100KL;RTT02104JH5;WR04X104 JHL;RM04JLN104 | Multiple |  | Purchase | SMT | 3 | PCS | R453 R457 R461 |
| 3 | B55.01107.M010 | 63.12334.1DL | CHIP RES 12K J 1/16W 0402 | R2_SA;HF_SA;G_SA; | TA-I ; RALEC ; CYNTEC ; YAGEO | RM04JTN123 ; RTT02123JTH ; RR0510S-123-JN ; RC0402JR-0712KL | Multiple |  | Purchase | SMT | 1 | PCS | R28 |
| 3 | B55.01107.M010 | 63.22234.1DL | CHIP RES 2.2K J 1/16W 0402 | R2_SA;HF_SA;G_SA; | TA-I;RALEC;CYNTEC;YAGEO;WALSIN | RM04JTN222 ; RTT02222JTH ; RR0510S-222-JN ; RC0402JR-072K2L;WR04X222JTL | Multiple |  | Purchase | SMT | 8 | PCS | R266 R267 R268 R500 R502 R83 R86 R90 |
| 3 | B55.01107.M010 | 63.2R233.15L | CHIP RES 2.2 J 1/10W 0603 | R2_SA;HF_SA;G_SA; | TA-I ; RALEC ; YAGEO ; WALSIN | RM06JTN2R2 ; RTT032R2JTP ; RC0603JR-072R2L ; WR06X2R2JTL | Multiple |  | Purchase | SMT | 1 | PCS | R483 |
| 3 | B55.01107.M010 | 63.2R734.15L | CHIP RES 2.7 J 1/10W 0603 | R2_SA;HF_SA;G_SA; | TA-I ; RALEC ; YAGEO | RM06JTN2R7 ; RTT032R7JTP ; RC0603JR-072R7L | Multiple |  | Purchase | SMT | 2 | PCS | R466 R837 |
| 3 | B55.01107.M010 | 63.33034.1DL | CHIP RES 33 J 1/16W 0402 | R2_SA;HF_SA;G_SA; | TA-I;RALEC;CYNTEC;YAGEO;WALSIN | RM04JTN330 ; RTT02330JTH ; RR0510S-330-JN ; RC0402JR-0733RL;WR04X330JTL | Multiple |  | Purchase | SMT | 3 | PCS | R306 R763 R766 |
| 3 | B55.01107.M010 | 63.33234.1DL | CHIP RES 3.3K J 1/16W 0402 | R2_SA;HF_SA;G_SA; | TA-I;RALEC;CYNTEC;YAGEO;WALSIN | RM04JTN332;RTT02332JTH;RR-0510S-332-JN;RC0402JR-073K3L;WR04X332JTL | Multiple |  | Purchase | SMT | 1 | PCS | R468 |
| 3 | B55.01107.M010 | 63.82234.1DL | CHIP RES 8.2K J 1/16W 0402 | R2_SA;HF_SA;G_SA; | TA-I;RALEC;CYNTEC;YAGEO;WALSIN | RM04JTN822 ; RTT02822JTH ; RR0510S-822-JN ; RC0402JR-078K2L;WR04X822JTL | Multiple |  | Purchase | SMT | 7 | PCS | R136 R137 R138 R139 R338 R340 R65 |
| 3 | B55.01107.M010 | 63.R0031.16L | CHIP RES 0 J 1/8W 0805 | R2_SA;HF_SA;G_SA; | TAI;RALEC;YAGEO;WALSIN | RM10JTN0 ; RTT05000JTP ; RC0805JR-070RL ; WR08X000PTL | Multiple |  | Purchase | SMT | 5 | PCS | R504 R529 R536 R709 R710 |
| 3 | B55.01107.M010 | 63.R0032.11L | CHIP RES 0 J 1/4W 1206 (ROHS) | R2_SA;HF_SA;G_SA; | TA-I ; RALEC ; YAGEO; WALSIN | RM12JTN0 ; RTT06000JTP ; RC1206JR-070RL; WR12X000 PTL | Multiple |  | Purchase | SMT | 4 | PCS | R479 R480 R481 R512 |
| 3 | B55.01107.M010 | 63.R0034.1DL | CHIP RES 0 J 1/16W 0402 | R2_SA;HF_SA;G_SA; | TAI;RALEC;CYNTEC;YAGEO;WALSIN | RM04JTN0;RTT02000JTH;RR0510X-000-XN;RC0402JR-070RL;WR04X000PTL | Multiple |  | Purchase | SMT | 152 | PCS | R10 R100 R123 R124 R127 R128 R129 R130 R131 R132 R14 R15 R151 R152 R153 R154 R155 R156 R157 R158 R159 R160 R161 R162 R163 R164 R165 R166 R167 R168 R169 R170 R171 R172 R173 R174 R175 R176 R177 R178 R239 R26 R278 R279 R281 R286 R288 R289 R290 R291 R292 R293 R294 R295 R297 R298 R301 R302 R312 R314 R316 R317 R318 R319 R320 R321 R322 R325 R326 R328 R329 R333 R334 R335 R342 R343 R344 R350 R356 R368 R38 R39 R4 R403 R406 R411 R417 R418 R419 R426 R427 R436 R452 R459 R46 R460 R485 R498 R5 R508 R510 R516 R517 R522 R525 R528 R533 R535 R540 R542 R556 R557 R558 R559 R607 R617 R651 R7 R711 R712 R713 R714 R715 R717 R718 R720 R724 R727 R731 R732 R736 R74 R768 R769 R770 R771 R772 R773 R780 R781 R795 R796 R797 R8 R808 R810 R820 R9 R92 R96 R98 R99 |
| 3 | B55.01107.M010 | 64.10006.6DL | CHIP RES 100 D 1/16W 0402 | R2_SA;HF_SA;G_SA; | RALEC;TAI;CYNTEC;YAGEO | RTT021000DTH;RM04DTN1000;RR0510P-101-DN;RC0402DR-07100RL | Multiple |  | Purchase | SMT | 2 | PCS | R432 R434 |
| 3 | B55.01107.M010 | 64.10015.6DL | CHIP RES 1K F 1/16W 0402 | R2_SA;HF_SA;G_SA; | TA-I;RALEC;CYNTEC;YAGEO;WALSIN | RM04FTN1001 ; RTT021001FTH ; RR0510S-102-FN ; RC0402FR-071KL;WR04X1001FTL | Multiple |  | Purchase | SMT | 17 | PCS | R198 R199 R404 R405 R410 R412 R415 R523 R695 R774 R776 R779 R813 R814 R815 R816 R821 |
| 3 | B55.01107.M010 | 64.10016.6DL | CHIP RES 1K D 1/16W 0402 | R2_SA;HF_SA;G_SA; | RALEC ; CYNTEC ; TA-I ; YAGEO | RTT021001DTH ; RR0510Q-102-DN ; RM04DTN1001 ; RT0402DRE071KL | Multiple |  | Purchase | SMT | 2 | PCS | R141 R143 |
| 3 | B55.01107.M010 | 64.10025.6DL | CHIP RES 10K F 1/16W 0402 | R2_SA;HF_SA;G_SA; | TA-I;RALEC;CYNTEC;YAGEO;WALSIN | RM04FTN1002 ; RTT021002FTH ; RR0510S-103-FN ; RC0402FR-0710KL;WR04X1002FTL | Multiple |  | Purchase | SMT | 30 | PCS | R24 R305 R307 R315 R351 R358 R359 R360 R361 R467 R478 R487 R49 R499 R507 R513 R518 R532 R539 R56 R64 R708 R72 R742 R78 R783 R784 R82 R825 R826 |
| 3 | B55.01107.M010 | 64.10035.6DL | CHIP RES 100K F 1/16W 0402 | R2_SA;HF_SA;G_SA; | TA-I;RALEC;CYNTEC;YAGEO;WALSIN | RM04FTN1003 ; RTT021003FTH ; RR0510S-104-FN ; RC0402FR-07100KL;WR04X1003FTL | Multiple |  | Purchase | SMT | 13 | PCS | R140 R146 R147 R148 R149 R275 R349 R437 R610 R743 R80 R85 R88 |
| 3 | B55.01107.M010 | 64.10045.6DL | CHIP RES 1M F 1/16W 0402 | R2_SA;HF_SA;G_SA; | TA-I;RALEC;CYNTEC;YAGEO;WALSIN | RM04FTN1004;RTT021004FTH;RR0510S-105-FN;RC0402FR-071ML;WR04X1004FTL | Multiple |  | Purchase | SMT | 5 | PCS | R27 R37 R45 R47 R503 |
| 3 | B55.01107.M010 | 64.10R05.16L | CHIP RES 10 F 1/8W 0805(ROHS) | R2_SA;HF_SA;G_SA; | TAI;YAGEO;RALEC | RM10FTN10R0;RC0805FR-0710RL;RTT0510R0FTP | Multiple |  | Purchase | SMT | 1 | PCS | R450 |
| 3 | B55.01107.M010 | 64.10R05.55L | CHIP RES 10 F 1/10W 0603 | R2_SA;HF_SA;G_SA; | TA-I;RALEC;YAGEO;WALSIN | RM06FTN10R0 ; RTT0310R0FTP ; RC0603FR-0710RL;WR06X10R0FTL | Multiple |  | Purchase | SMT | 4 | PCS | R473 R489 R514 R829 |
| 3 | B55.01107.M010 | 64.10R05.6DL | CHIP RES 10 F 1/16W 0402 | R2_SA;HF_SA;G_SA; | TAI;RALEC;CYNTEC;YAGEO;WALSIN | RM04FTN10R0;RTT0210R0FTH;RR0510S-100-FN;RC0402FR-0710RL;WR04X10R0FTL | Multiple |  | Purchase | SMT | 5 | PCS | R431 R440 R441 R442 R443 |
| 3 | B55.01107.M010 | 64.11025.6DL | CHIP RES 11K F 1/16W 0402 | R2_SA;HF_SA;G_SA; | TA-I ; RALEC ; CYNTEC ; YAGEO;WALSIN | RM04FTN1102 ; RTT021102FTH ; RR0510S-1102-FN ; RC0402FR-0711KL;WR04X1102FTL | Multiple |  | Purchase | SMT | 2 | PCS | R439 R744 |
| 3 | B55.01107.M010 | 64.12005.55L | CHIP RES 120 F 1/10W 0603 | R2_SA;HF_SA;G_SA; | TA-I ; RALEC ; YAGEO | RM06FTN1200 ; RTT031200FTP ; RC0603FR-07120RL | Multiple |  | Purchase | SMT | 1 | PCS | R737 |
| 3 | B55.01107.M010 | 64.12005.6DL | CHIP RES 120 F 1/16W 0402 | R2_SA;HF_SA;G_SA; | TAI;RALEC;CYNTEC;YAGEO | RM04FTN1200;RTT021200FTH;RR0510S-121-FN;RC0402FR-07120RL | Multiple |  | Purchase | SMT | 48 | PCS | R209 R210 R211 R212 R215 R216 R217 R218 R220 R221 R222 R223 R225 R226 R227 R228 R229 R230 R231 R232 R233 R234 R235 R236 R237 R238 R240 R241 R242 R243 R244 R245 R246 R247 R248 R249 R250 R251 R252 R253 R254 R255 R256 R257 R258 R259 R260 R261 |
| 3 | B55.01107.M010 | 64.13005.55L | CHIP RES 130 F 1/10W 0603 | R2_SA;HF_SA;G_SA; | TA-I ; RALEC ; YAGEO | RM06FTN1300 ; RTT031300FTP ; RC0603FR-07130RL | Multiple |  | Purchase | SMT | 1 | PCS | R817 |
| 3 | B55.01107.M010 | 64.13725.6DL | CHIP RES 13.7K F 1/16W 0402 | R2_SA;HF_SA;G_SA; | TA-I;RALEC;CYNTEC;YAGEO | RM04FTN1372;RTT021372FTH;RR0510S-1372-FN;RC0402FR-0713K7L | Multiple |  | Purchase | SMT | 1 | PCS | R515 |
| 3 | B55.01107.M010 | 64.14015.6DL | CHIP RES 1.4K F 1/16W 0402(ROHS) | R2_SA;HF_SA;G_SA; | CYNTEC;RALTEC;TAI;YAGEO | RR0510S-1401-FN;RTT021401FTH;RM04FTN1401;RC0402FR-071K4L | Multiple |  | Purchase | SMT | 3 | PCS | R407 R409 R819 |
| 3 | B55.01107.M010 | 64.14735.L1L | CHIP RES 147K F 1/16W 0402 | R2_SA;HF_SA;G_SA; | TA-I;RALEC;CYNTEC;WALSIN | RM04FTN1473;RTT021473FTH;RR0510S-1473-FN;WR04X1473FTL | Multiple |  | Purchase | SMT | 1 | PCS | R843 |
| 3 | B55.01107.M010 | 64.15005.6DL | CHIP RES 150 F 1/16W 0402 | R2_SA;HF_SA;G_SA; | TAI;RALEC;CYNTEC;YAGEO;WALSIN | RM04FTN1500 ; RTT021500FTH ; RR0510S-1500-FN ; RC0402FR-07150RL;WR04X1500FTL | Multiple |  | Purchase | SMT | 1 | PCS | R346 |
| 3 | B55.01107.M010 | 64.15025.6DL | CHIP RES 15K F 1/16W 0402 | R2_SA;HF_SA;G_SA; | TA-I;RALEC;CYNTEC;YAGEO | RM04FTN1502;RTT021502FTH;RR0510S-153-FN;RC0402FR-0715KL | Multiple |  | Purchase | SMT | 3 | PCS | R471 R491 R521 |
| 3 | B55.01107.M010 | 64.16915.6DL | CHIP RES 1.69K F 1/16W 0402 | R2_SA;HF_SA;G_SA; | TAI;RALEC;YAGEO;CYNTEC | RM04FTN1691;RTT021691FTH;RC0402FR-071K69L;RR0510S-1691-FN | Multiple |  | Purchase | SMT | 1 | PCS | R506 |
| 3 | B55.01107.M010 | 64.20005.6DL | CHIP RES 200 F 1/16W 0402 | R2_SA;HF_SA;G_SA; | TA-I;RALEC;CYNTEC;WALSIN;YAGEO | RM04FTN2000;RTT022000FTH;RR0510S-201-FN;WR04X2000FTL;RC0402FR-07200RL | Multiple |  | Purchase | SMT | 1 | PCS | R142 |
| 3 | B55.01107.M010 | 64.20015.6DL | CHIP RES 2K F 1/16W 0402 | R2_SA;HF_SA;G_SA; | TA-I;RALEC;CYNTEC;YAGEO;WALSIN | RM04FTN2001 ; RTT022001FTH ; RR0510S-202-FN ; RC0402FR-072KL;WR04X2001FTL | Multiple |  | Purchase | SMT | 1 | PCS | R836 |
| 3 | B55.01107.M010 | 64.20025.6DL | CHIP RES 20K F 1/16W 0402 | R2_SA;HF_SA;G_SA; | TA-I;RALEC;CYNTEC;YAGEO;WALSIN | RM04FTN2002 ; RTT022002FTH ; RR0510S-203-FN ; RC0402FR-0720KL;WR04X2002FTL | Multiple |  | Purchase | SMT | 3 | PCS | R193 R194 R831 |
| 3 | B55.01107.M010 | 64.20035.6DL | CHIP RES 200K F 1/16W 0402 | R2_SA;HF_SA;G_SA; | TA-I;RALEC;CYNTEC;YAGEO;WALSIN | RM04FTN2003 ; RTT022003FTH ; RR0510S-204-FN ; RC0402FR-07200KL;WR04X2003FTL | Multiple |  | Purchase | SMT | 3 | PCS | R470 R833 R834 |
| 3 | B55.01107.M010 | 64.22015.6DL | CHIP RES 2.2K F 1/16W 0402 | R2_SA;HF_SA;G_SA; | TA-I;RALEC;CYNTEC;YAGEO | RM04FTN2201;RTT022201FTH;RR0510S-222-FN;RC0402FR-072K2L | Multiple |  | Purchase | SMT | 22 | PCS | R179 R180 R181 R182 R183 R184 R185 R186 R187 R188 R191 R192 R195 R196 R197 R200 R201 R202 R203 R204 R274 R296 |
| 3 | B55.01107.M010 | 64.22625.6DL | CHIP RES 22.6K F 1/16W 0402 | R2_SA;HF_SA;G_SA; | RALEC;CYNTEC;TA-I;YAGEO;WALSIN | RTT022262FTH ; RR0510S-2262-FN ; RM04FTN2262 ; RC0402FR-0722K6L;WR04X2262JTL | Multiple |  | Purchase | SMT | 1 | PCS | R462 |
| 3 | B55.01107.M010 | 64.24005.6DL | CHIP RES 240 F 1/16W 0402(ROHS | R2_SA;HF_SA;G_SA; | TA-I ; RALEC ; CYNTEC ; YAGEO | RM04FTN2400 ; RTT022400FTH ; RR0510S-241-FN ; RC0402FR-07240RL | Multiple |  | Purchase | SMT | 2 | PCS | R145 R219 |
| 3 | B55.01107.M010 | 64.24915.6DL | CHIP RES 2.49K F 1/16W 0402 | R2_SA;HF_SA;G_SA; | TA-I;RALEC;CYNTEC;YAGEO;WALSIN | RM04FTN2491;RTT022491FTH;RR0510S-2491-FN;RC0402FR-072K49L;WR04X2491FTL | Multiple |  | Purchase | SMT | 1 | PCS | R530 |
| 3 | B55.01107.M010 | 64.26125.6DL | CHIP RES 26.1K F 1/16W 0402 | R2_SA;HF_SA;G_SA; | TAI;RALEC;CYNTEC;YAGEO | RM04FTN2612;RTT022612FTH;RR0510S-2612-FN;RC0402FR-0726K1L | Multiple |  | Purchase | SMT | 1 | PCS | R435 |
| 3 | B55.01107.M010 | 64.27015.6DL | CHIP RES 2.7K F 1/16W 0402 | R2_SA;HF_SA;G_SA; | TAI;RALEC;CYNTEC;YAGEO | RM04FTN2701;RTT022701FTH;RR0510S-2701-FN;RC0402FR-072K7L | Multiple |  | Purchase | SMT | 3 | PCS | R214 R413 R488 |
| 3 | B55.01107.M010 | 64.2R205.55L | CHIP RES 2.2 F 1/10W 0603 | R2_SA;HF_SA;G_SA; | TAI;YAGEO;RALEC;WALSIN | RM06FTN2R20;RC0603FR-072R2L;RTT032R20FTP;WR06W2R20FTL | Multiple |  | Purchase | SMT | 3 | PCS | R464 R511 R832 |
| 3 | B55.01107.M010 | 64.30005.6DL | CHIP RES 300 F 1/16W 0402 | R2_SA;HF_SA;G_SA; | CYNTEC;RALEC;TAI;YAGEO | RR0510S-301-FN;RTT023000FTH;RM04FTN3000;RC0402FR-07300RL | Multiple |  | Purchase | SMT | 1 | PCS | R91 |
| 3 | B55.01107.M010 | 64.30935.6DL | CHIP RES 309K F 1/16W 0402 | R2_SA;HF_SA;G_SA; | TA-I;RALEC;CYNTEC;YAGEO | RM04FTN3093;RTT023093FTH;RR0510S-3093-FN;RC0402FR-07309KL | Multiple |  | Purchase | SMT | 1 | PCS | R844 |
| 3 | B55.01107.M010 | 64.33005.6DL | CHIP RES 330 F 1/16W 0402 | R2_SA;HF_SA;G_SA; | CYNTEC;RALEC;TAI;YAGEO | RR0510S-331-FN;RTT023300FTH;RM04FTN3300;RC0402FR-07330RL | Multiple |  | Purchase | SMT | 1 | PCS | R402 |
| 3 | B55.01107.M010 | 64.33R05.6DL | CHIP RES 33 F 1/16W 0402 | R2_SA;HF_SA;G_SA; | TA-I;RALEC;CYNTEC;YAGEO;WALSIN | RM04FTN33R0;RTT0233R0FTH;RR0510S-330-FN;RC0402FR-0733RL;WR04X33R0FTL | Multiple |  | Purchase | SMT | 9 | PCS | R270 R277 R280 R283 R284 R51 R52 R58 R59 |
| 3 | B55.01107.M010 | 64.33R25.6DL | CHIP RES 33.2 F 1/16W 0402 | R2_SA;HF_SA;G_SA; | TA-I;RALEC;CYNTEC;YAGEO | RM04FTN33R2;RTT0233R2FTH;RR0510S-33R2-FN;RC0402FR-0733R2L | Multiple |  | Purchase | SMT | 1 | PCS | R89 |
| 3 | B55.01107.M010 | 64.35715.6DL | CHIP RES 3.57K F 1/16W 0402 | R2_SA;HF_SA;G_SA; | TA-I;RALEC;CYNTEC;YAGEO | RM04FTN3571;RTT023571FTH;RR0510S-3571-FN;RC0402FR-073K57L | Multiple |  | Purchase | SMT | 1 | PCS | R505 |
| 3 | B55.01107.M010 | 64.39225.6DL | CHIP RES 39.2K F 1/16W 0402 | R2_SA;HF_SA;G_SA; | TA-I;RALEC;CYNTEC;YAGEO;WALSIN | RM04FTN3922 ; RTT023922FTH ; RR0510S-3922-FN ; RC0402FR-0739K2L;WR04X3922FTL | Multiple |  | Purchase | SMT | 2 | PCS | R433 R841 |
| 3 | B55.01107.M010 | 64.3R015.16L | CHIP RES 3.01 F 1/8W 0805 | R2_SA;HF_SA;G_SA; | TA-I;RALEC | RM10FTN3R01;RTT053R01FTP | Multiple |  | Purchase | SMT | 1 | PCS | R484 |
| 3 | B55.01107.M010 | 64.44225.6DL | CHIP RES 44.2K F 1/16W 0402 | R2_SA;HF_SA;G_SA; | TAI;RALEC;CYNTEC;YAGEO;WALSIN | RM04FTN4422;RTT024422FTH;RR0510S-4422-FN;RC0402FR-0744K2L;WR04X4422FTL | Multiple |  | Purchase | SMT | 2 | PCS | R496 R840 |
| 3 | B55.01107.M010 | 64.46415.6DL | CHIP RES 4.64K F 1/16W 0402 | R2_SA;HF_SA;G_SA; | RALEC;TAI;YAGEO;CYNTEC | RTT024641FTH;RM04FTN4641;RC0402FR-074K64L;RR0510S-4641-FN | Multiple |  | Purchase | SMT | 1 | PCS | R538 |
| 3 | B55.01107.M010 | 64.47015.6DL | CHIP RES 4.7K F 1/16W 0402 | R2_SA;HF_SA;G_SA; | TA-I;RALEC;CYNTEC;YAGEO;WALSIN | RM04FTN4701;RTT024701FTH;RR0510S-472-FN;RC0402FR-074K7L;WR04X4701FTL | Multiple |  | Purchase | SMT | 79 | PCS | R105 R20 R22 R23 R262 R263 R264 R265 R271 R276 R29 R299 R3 R30 R308 R31 R310 R313 R32 R324 R327 R33 R331 R337 R339 R34 R341 R35 R352 R353 R36 R369 R370 R375 R379 R383 R385 R386 R387 R394 R395 R396 R397 R398 R408 R420 R422 R423 R424 R425 R48 R544 R551 R552 R553 R554 R555 R599 R601 R697 R699 R700 R701 R702 R703 R721 R723 R725 R726 R728 R740 R801 R802 R803 R804 R805 R807 R811 R84 |
| 3 | B55.01107.M010 | 64.47025.6DL | CHIP RES 47K F 1/16W 0402 | R2_SA;HF_SA;G_SA; | TA-I;RALEC;CYNTEC;YAGEO;WALSIN | RM04FTN4702;RTT024702FTH;RR0510S-473-FN;RC0402FR-0747KL;WR04X4702FTL | Multiple |  | Purchase | SMT | 3 | PCS | R303 R304 R76 |
| 3 | B55.01107.M010 | 64.47035.6DL | CHIP RES 470K F 1/16W 0402 | R2_SA;HF_SA;G_SA; | TA-I;RALEC;CYNTEC;YAGEO;WALSIN | RM04FTN4703;RTT024703FTH;RR0510S-474-FN;RC0402FR-07470KL;WR04X4703FTL | Multiple |  | Purchase | SMT | 1 | PCS | R79 |
| 3 | B55.01107.M010 | 64.47515.6DL | CHIP RES 4.75K F 1/16W 0402 | R2_SA;HF_SA;G_SA; | TA-I;RALEC;CYNTEC;YAGEO | RM04FTN4751;RTT024751FTH;RR0510S-4751-FN;RC0402FR-074K75L | Multiple |  | Purchase | SMT | 3 | PCS | R71 R73 R81 |
| 3 | B55.01107.M010 | 64.47535.6DL | CHIP RES 475K F 1/16W 0402 | R2_SA;HF_SA;G_SA; | TA-I;RALEC;CYNTEC;YAGEO | RM04FTN4753;RTT024753FTH;RR0510S-4753-FN;RC0402FR-07475KL | Multiple |  | Purchase | SMT | 1 | PCS | R492 |
| 3 | B55.01107.M010 | 64.49905.6DL | CHIP RES 499 F 1/16W 0402 | R2_SA;HF_SA;G_SA; | TA-I ; RALEC ; CYNTEC ; YAGEO | RM04FTN4990 ; RTT024990FTH ; RR0510S-4990-FN ; RC0402FR-07499RL | Multiple |  | Purchase | SMT | 2 | PCS | R189 R190 |
| 3 | B55.01107.M010 | 64.49915.6DL | CHIP RES 4.99K F 1/16W 0402 | R2_SA;HF_SA;G_SA; | TA-I;RALEC;CYNTEC;YAGEO;WALSIN | RM04FTN4991 ; RTT024991FTH ; RR0510S-4991-FN ; RC0402FR-074K99L ; WR04X4991FTL | Multiple |  | Purchase | SMT | 1 | PCS | R531 |
| 3 | B55.01107.M010 | 64.49925.6DL | CHIP RES 49.9K F 1/16W 0402 | R2_SA;HF_SA;G_SA; | TA-I ; RALEC ; CYNTEC ; YAGEO ; WALSIN | RM04FTN4992 ; RTT024992FTH ; RR0510S-4992-FN ; RC0402FR-0749K9L ; WR04X4992FTL | Multiple |  | Purchase | SMT | 3 | PCS | R366 R445 R446 |
| 3 | B55.01107.M010 | 64.57626.6DL | CHIP RES 57.6K D 1/16W 0402 | R2_SA;HF_SA;G_SA; | RALEC ; CYNTEC ; TA-I ; YAGEO | RTT025762DTH ; RR0510Q-5762-DN ; RM04DTN5762 ; RC0402DR-0757K6L | Multiple |  | Purchase | SMT | 2 | PCS | R475 R494 |
| 3 | B55.01107.M010 | 64.60R45.6DL | CHIP RES 60.4 F 1/16W 0402 | R2_SA;HF_SA;G_SA; | TA-I;RALEC;CYNTEC;YAGEO;WALSIN | RM04FTN60R4;RTT0260R4FTH;RR0510S-60R4-FN;RC0402FR-0760R4L;WR04X60R4FTL | Multiple |  | Purchase | SMT | 2 | PCS | R205 R206 |
| 3 | B55.01107.M010 | 64.66525.6DL | CHIP RES 66.5K F 1/16W 0402 | R2_SA;HF_SA;G_SA; | TAI;RALEC;CYNTEC;YAGEO;WALSIN | RM04FTN6652;RTT026652FTH;RR0510S-6652-FN;RC0402FR-0766K5L;WR04X6652FAL | Multiple |  | Purchase | SMT | 1 | PCS | R454 |
| 3 | B55.01107.M010 | 64.73225.6DL | CHIP RES 73.2K F 1/16W 0402 | R2_SA;HF_SA;G_SA; | TA-I;RALEC;CYNTEC;YAGEO;WALSIN | RM04FTN7322;RTT027322FTH;RR0510S-7322-FN;RC0402FR-0773K2L;WR04X7322FTL | Multiple |  | Purchase | SMT | 1 | PCS | R474 |
| 3 | B55.01107.M010 | 64.78715.6DL | CHIP RES 7.87K F 1/16W 0402 | R2_SA;HF_SA;G_SA; | TA-I;RALEC;CYNTEC;YAGEO | RM04FTN7871;RTT027871FTH;RR0510S-7871-FN;RC0402FR-077K87L | Multiple |  | Purchase | SMT | 1 | PCS | R401 |
| 3 | B55.01107.M010 | 64.86605.6DL | CHIP RES 866 F 0402 1/16W | R2_SA;HF_SA;G_SA; | RALEC;TA-I;YAGEO;WALSIN | RTT028660FTH;RM04FTN8660;RC0402FR-07866RL;WR04X8660FTL | Multiple |  | Purchase | SMT | 1 | PCS | R778 |
| 3 | B55.01107.M010 | 64.86625.6DL | CHIP RES 86.6K F 1/16W 0402 | R2_SA;HF_SA;G_SA; | TA-I;RALEC;CYNTEC;YAGEO | RM04FTN8662;RTT028662FTH;RR0510S-8662-FN;RC0402FR-0786K6L | Multiple |  | Purchase | SMT | 1 | PCS | R458 |
| 3 | B55.01107.M010 | 64.R0025.L1L | CHIP RES 0.002 F 1W 0612 | R2_SA;HF_SA; | CYNTEC | RL1632L4-R002-FN | Multiple |  | Purchase | SMT | 1 | PCS | R444 |
| A | B55.01107.M010 | 64.R0025.L0L | CHIP RES 0.002 F 1W 0612 | R2_SA;HF_SA; | VISHAY;CYNTEC | WSK06122L000FEA;RL1632L4-R002-FN |  |  | Purchase |  |  |  |  |
| 3 | B55.01107.M010 | 68.00084.831 | CHIP BEAD BLM21PG220SN1D (LF) | R2_SA;HF_SA; | MURATA | BLM21PG220SN1D | Multiple |  | Purchase | SMT | 3 | PCS | L30 L6 L8 |
| A | B55.01107.M010 | 68.00216.081 | CHIP BEAD HCB2012KF-220T60 | R2_SA;HF_SA; | TAITECH | HCB2012KF-220T60 |  |  | Purchase |  |  |  |  |
| 3 | B55.01107.M010 | 68.00084.A61 | CHIP BEAD BLM21PG300SN1D MURAT | R2_SA;HF_SA; | MURATA | BLM21PG300SN1D | Multiple |  | Purchase | SMT | 1 | PCS | L23 |
| A | B55.01107.M010 | 068.00002.0091 | CHIP BEAD BLM21SN300SN1D MURATA | R2_SA;HF_SA; | MURATA | BLM21SN300SN1D |  |  | Purchase |  |  |  |  |
| 3 | B55.01107.M010 | 68.00109.171 | CHIP BEAD MMZ2012S601ATA1N TDK | R2_SA;HF_SA; | TDK | MMZ2012S601ATA1N | Single |  | Purchase | SMT | 4 | PCS | L2 L3 L4 L5 |
| 3 | B55.01107.M010 | 68.1R010.20K | CHIP CHOKE 1.0UH PCMB103T-1R0MS | R2_SA;HF_SA;G_SA; | CYNTEC | PCMB103T-1R0MS | Multiple |  | Purchase | SMT | 1 | PCS | L31 |
| A | B55.01107.M010 | 68.1R01E.10H | CHIP IND 1.0UH M MMD-10CZ-1R0M-X2W | R2_SA;HF_SA; | MAGLAYER | MMD-10CZ-1R0M-X2W |  |  | Purchase |  |  |  |  |
| 3 | B55.01107.M010 | 68.3R310.20V | CHIP CHOKE 3.3UH PCMB063T-3R3MS | R2_SA;HF_SA; | CYNTEC | PCMB063T-3R3MS | Multiple |  | Purchase | SMT | 1 | PCS | L9 |
| A | B55.01107.M010 | 68.3R31A.10V | CHIP IND 3.3UH MMD-06CZ-3R3M-V | R2_SA;HF_SA;G_SA; | MAGLAYER | MMD-06CZ-3R3M-V1W |  |  | Purchase |  |  |  |  |
| 3 | B55.01107.M010 | 68.4R71A.20Q | CHIP CHOKE 4.7UH M PCMB104T-4R7MS | R2_SA;HF_SA; | CYNTEC | PCMB104T-4R7MS | Multiple |  | Purchase | SMT | 1 | PCS | L7 |
| A | B55.01107.M010 | 68.4R71D.10U | CHIP IND 4.7UH MMD-10DZ-4R7M-X2W | R2_SA;HF_SA; | MAGLAYER | MMD-10DZ-4R7M-X2W |  |  | Purchase |  |  |  |  |
| 3 | B55.01107.M010 | 71.00551.00A | IC CLK BUF ICS551MLFT SOIC 8P | R2_SA;HF_SA; | IDT | ICS551MLFT | Single |  | Purchase | SMT | 1 | PCS | U30 |
| 3 | B55.01107.M010 | 71.02514.F03 | IC USB HUB USB2514B-AEZC-TR QFN 36P | R2_SA;HF_SA; | SMSC | USB2514B-AEZC-TR | Single |  | Purchase | SMT | 1 | PCS | U99 |
| 3 | B55.01107.M010 | 72.24C64.K01 | IC EEPROM M24C64-RMN6TP SOIC 8P | R2_SA;HF_SA; | STMICROELECTRONICS INC | M24C64-RMN6TP | Multiple |  | Purchase | SMT | 1 | PCS | U26 |
| A | B55.01107.M010 | 072.02464.0A01 | IC EEPROM FM24C64D-SO-T-G SOP 8P | R2_SA;HF_SA; | FUDAN | FM24C64D-SO-T-G |  |  | Purchase |  |  |  |  |
| 3 | B55.01107.M010 | 73.01G07.01H | IC BUF SN74LVC1G07DCKRG4 DCK5P | R2_SA;HF_SA; | TI | SN74LVC1G07DCKRG4 | Multiple |  | Purchase | SMT | 1 | PCS | U9 |
| A | B55.01107.M010 | 73.01G07.AHG | IC SUF/DRI U74LVC1G07G-AL5-R SOT-353 | R2_SA;HF_SA; | UTC | U74LVC1G07G-AL5-R |  |  | Purchase |  |  |  |  |
| 3 | B55.01107.M010 | 73.01G08.L03 | IC CMOS SN74LVC1G08DCKR SC-70 | R2_SA;HF_SA;G_SA; | TI | SN74LVC1G08DCKR | Multiple |  | Purchase | SMT | 4 | PCS | U31 U37 U38 U46 |
| A | B55.01107.M010 | 073.7SZ08.000G | IC CMOS TC7SZ08FU,LJ(CT SSOP5-P-0.65A | R2_SA;HF_SA; | TOSHIBA | TC7SZ08FU,LJ(CT |  |  | Purchase |  |  |  |  |
| A | B55.01107.M010 | 73.01G08.DHG | IC CMOS SN74LVC1G08DCKRG4 DCK | R2_SA;HF_SA;G_SA; | TI | SN74LVC1G08DCKRG4 |  |  | Purchase |  |  |  |  |
| 3 | B55.01107.M010 | 73.01G14.AHG | IC CMOS SN74LVC1G14DBVR SOT-23 | R2_SA;HF_SA; | TI | SN74LVC1G14DBVR | Multiple |  | Purchase | SMT | 1 | PCS | U106 |
| A | B55.01107.M010 | 73.7SZ14.BAG | IC CMOS NC7SZ14M5X SOT-23-5 | R2_SA;HF_SA; | FAIRCHILD | NC7SZ14M5X |  |  | Purchase |  |  |  |  |
| 3 | B55.01107.M010 | 73.01G14.L05 | IC CMOS 74LVC1G14DCKR SC-70(GP | R2_SA;HF_SA;G_SA; | TI | SN74LVC1G14DCKR | Multiple |  | Purchase | SMT | 1 | PCS | U102 |
| A | B55.01107.M010 | 073.7SZ14.000G | IC COMS TC7SZ14FU,LJ(CT SSOP5-P-0.65A | R2_SA;HF_SA; | TOSHIBA | TC7SZ14FU,LJ(CT |  |  | Purchase |  |  |  |  |
| A | B55.01107.M010 | 73.01G14.FHG | IC CMOS U74LVC1G14G-AL5-R SOT-353 | R2_SA;HF_SA; | UTC | U74LVC1G14G-AL5-R |  |  | Purchase |  |  |  |  |
| 3 | B55.01107.M010 | 73.02G07.A2J | IC CMOS 74LVC2G07GW SOT-363 6P | R2_SA;HF_SA; | NXP | 74LVC2G07GW | Multiple |  | Purchase | SMT | 1 | PCS | U5 |
| A | B55.01107.M010 | 73.02G07.02J | IC CMOS SN74LVC2G07DCKR SC-70 | R2_SA;HF_SA; | TI | SN74LVC2G07DCKR |  |  | Purchase |  |  |  |  |
| A | B55.01107.M010 | 73.7WZ07.0AJ | IC CMOS NC7WZ07P6X SC70-6 | R2_SA;HF_SA; | FAIRCHILD | NC7WZ07P6X |  |  | Purchase |  |  |  |  |
| 3 | B55.01107.M010 | 73.03245.F0B | IC BUS SW SN74CBTLV3245APWR TSSOP 20P | R2_SA;HF_SA; | TI | SN74CBTLV3245APWR | Single |  | Purchase | SMT | 2 | PCS | U105 U107 |
| 3 | B55.01107.M010 | 73.07W74.0A7 | IC CMOS TC7WZ74FK SSOP8-P-0.50A | R2_SA;HF_SA; | TOSHIBA | TC7WZ74FK | Multiple |  | Purchase | SMT | 1 | PCS | U19 |
| A | B55.01107.M010 | 73.01G74.0HF | IC CMOS SN74LVC1G74DCUR VSSOP-8P | R2_SA;HF_SA; | TI | SN74LVC1G74DCUR |  |  | Purchase |  |  |  |  |
| 3 | B55.01107.M010 | 73.1G126.DHG | IC CMOS SN74LVC1G126DCKR SC70 | R2_SA;HF_SA; | TI | SN74LVC1G126DCKR | Multiple |  | Purchase | SMT | 4 | PCS | U100 U101 U103 U104 |
| A | B55.01107.M010 | 073.7S126.000G | IC CMOS TC7SZ126FU,LJ(CT SSOP5-P-0.65A | R2_SA;HF_SA; | TOSHIBA | TC7SZ126FU,LJ(CT |  |  | Purchase |  |  |  |  |
| A | B55.01107.M010 | 73.7S126.AAH | IC CMOS NC7SZ126P5X SC70-5 | R2_SA;HF_SA; | FAIRCHILD | NC7SZ126P5X |  |  | Purchase |  |  |  |  |
| 3 | B55.01107.M010 | 73.74126.BHB | IC BUF SN74LVC126APWR TSSOP14P | R2_SA;HF_SA; | TI | SN74LVC126APWR | Multiple |  | Purchase | SMT | 1 | PCS | U32 |
| A | B55.01107.M010 | 73.74126.0HB | IC CMOS 74LVC126APW,118 TSSOP14P | R2_SA;HF_SA; | NXP | 74LVC126APW,118 |  |  | Purchase |  |  |  |  |
| 3 | B55.01107.M010 | 74.00075.B79 | IC TEMP SENSOR TMP75AIDGKR MSOP 8P | R2_SA;HF_SA; | TI | TMP75AIDGKR | Multiple |  | Purchase | SMT | 3 | PCS | U27 U84 U85 |
| A | B55.01107.M010 | 074.00752.M001 | IC TEMP SEN STTS75DS2F MSOP 8P(FIONA) | R2_SA;HF_SA; | ST | STTS75DS2F |  |  | Purchase |  |  |  |  |
| 3 | B55.01107.M010 | 74.00331.A2F | IC V.R LMV331IDCKRG4 SC-70 5P | R2_SA;HF_SA; | TI | LMV331IDCKRG4 | Multiple |  | Purchase | SMT | 1 | PCS | U10 |
| A | B55.01107.M010 | 74.00331.I2F | IC V.C AZV331KSTR-G1 SC-70 5P | R2_SA;HF_SA; | BCD | AZV331KSTR-G1 |  |  | Purchase |  |  |  |  |
| 3 | B55.01107.M010 | 74.02065.07F | IC PWR SW TPS2065DBVT SOT-23 5P | R2_SA;HF_SA; | TI | TPS2065DBVT | Single |  | Purchase | SMT | 1 | PCS | U98 |
| 3 | B55.01107.M010 | 74.53312.073 | IC PWM CTRL TPS53312RGTR QFN 16P | R2_SA;HF_SA; | TI | TPS53312RGTR | Single |  | Purchase | SMT | 1 | PCS | PU4 |
| 3 | B55.01107.M010 | 74.53318.073 | IC PWR CTRL TPS53318DQPR QFN 22P | R2_SA;HF_SA; | TI | TPS53318DQPR | Single |  | Purchase | SMT | 2 | PCS | PU1 PU2 |
| 3 | B55.01107.M010 | 74.53319.073 | IC PWR CTRL TPS53319DQPR QFN 22P | R2_SA;HF_SA; | TI | TPS53319DQPR | Single |  | Purchase | SMT | 1 | PCS | U81 |
| 3 | B55.01107.M010 | 74.74801.A33 | IC LDO TPS74801RGW QFN 20P | R2_SA;HF_SA; | TI | TPS74801RGW | Single |  | Purchase | SMT | 3 | PCS | PU10 PU11 PU9 |
| 3 | B55.01107.M010 | 75.005V0.A77 | IC DIODE ESD PESD5V0S1BL,315 SOD882 | R2_SA;HF_SA; | NEXPERIA | PESD5V0S1BL,315 | Single |  | Purchase | SMT | 5 | PCS | D13 D14 D15 D16 D17 |
| 3 | B55.01107.M010 | 77.21071.02L | CHIP CAP POS 100U 16V M7343 ESR | R2_SA;HF_SA; | PANASONIC | 16TQC100MYF | Multiple |  | Purchase | SMT | 1 | PCS | C167 |
| A | B55.01107.M010 | 077.C1071.0001 | CHIP CAP T 100U 16V M 7343 ESR50 | R2_SA;HF_SA; | KEMET | T521V107M016ATE0507034 |  |  | Purchase |  |  |  |  |
| 3 | B55.01107.M010 | 77.21571.18L | CHIP CAP POS 150U 16V M7343 | R2_SA;HF_SA; | PANASONIC | 16TQC150MYF | Multiple |  | Purchase | SMT | 2 | PCS | C168 C246 |
| A | B55.01107.M010 | 077.C1571.0001 | CHIP CAPACITOR POLY T 150U 16V M 7343 | R2_SA;HF_SA; | KEMET | T521D157M016ATE055 |  |  | Purchase |  |  |  |  |
| 3 | B55.01107.M010 | 78.10134.1FL | CHIP CAP C 100P 50V J0402 NPO | R2_SA;HF_SA;G_SA; | AVX;DARFON;MURATA;PHYCOMP;SAMSUNG;TAIYO;WALSIN;YAGEO | CM05CG101J50AH;C1005NP0101JGT;GRM1555C1H101JA01D;223886915101;CL05C101JB5NNNC;UMK105CH101JV-F;0402N101J500CT;CC0402JRNPO9BN101 | Multiple |  | Purchase | SMT | 6 | PCS | C105 C206 C88 C91 C94 C96 |
| 3 | B55.01107.M010 | 78.10224.2FL | CHIP CAP C 1000P 50V K0402 X7R | R2_SA;R_SA;HF_SA;G_SA; | AVX;DARFON;MURATA;PHYCOMP;SAMSUNG;TAIYO;MURATA;AVX;YAGEO | CM05X7R102K50AH;C1005X7R102KGT;GRM155R71H102KA01D;223858715623;CL05B102KB5NNNC;UMK105B7102KV-F;WBM155R71H102KA01D;04025C102KAT2A;CC0402KRX7R9BB102 | Multiple |  | Purchase | SMT | 3 | PCS | C129 C162 C183 |
| 3 | B55.01107.M010 | 78.10322.2FL | CHIP CAP C 0.01U 25V K0402 X7R | R2_SA;HF_SA;G_SA; | AVX;DARFON;MURATA;PHYCOMP;SAMSUNG;TAIYO;TDK;MURATA;YAGEO | 04023C103KAT2A;C1005X7R103KFT;GRM155R71E103KA01D;223891715636;CL05B103KA5NNNC;TMK105BJ103KV-F;C1005X7R1E103KT000F;WBM155R71E103KA01D;CC0402KRX7R8BB103 | Multiple |  | Purchase | SMT | 3 | PCS | C131 C53 C76 |
| 3 | B55.01107.M010 | 78.10421.2FL | CHIP CAP C 0.1U 16V K0402 X7R | R2_SA;HF_SA;G_SA; | DARFON;MURATA;PHYCOMP;SAMSUNG;TAIYO;WALSIN;YAGEO | C1005X7R104KET;GRM155R71C104KA88D;223878715649;CL05B104KO5NNNC;EMK105B7104KV-F;0402B104K160CT;CC0402KRX7R7BB104 | Multiple |  | Purchase | SMT | 81 | PCS | C1 C103 C126 C127 C130 C135 C136 C141 C169 C186 C195 C198 C203 C214 C227 C230 C239 C242 C27 C30 C33 C34 C36 C37 C38 C39 C41 C44 C485 C49 C502 C503 C504 C505 C506 C508 C51 C513 C55 C601 C602 C605 C607 C608 C609 C612 C613 C615 C616 C618 C619 C620 C623 C624 C626 C628 C629 C630 C631 C632 C633 C634 C639 C641 C653 C659 C66 C67 C68 C69 C70 C71 C72 C73 C74 C75 C78 C79 C80 C93 C999 |
| 3 | B55.01107.M010 | 78.10422.2FL | CHIP CAP C 0.1U 25V K0402 X7R | R2_SA;HF_SA;G_SA; | YAGEO;WALSIN;MURATA;SAMSUNG;TAIYO;DARFON | CC0402KRX7R8BB104;0402B104K250CT;GRM155R71E104KE14D;CL05B104KA5NNNC;TMK105B7104KV-FR;C1005X7R104KFT | Multiple |  | Purchase | SMT | 14 | PCS | C117 C118 C120 C122 C123 C125 C138 C181 C189 C518 C519 C520 C522 C627 |
| 3 | B55.01107.M010 | 78.10424.2BL | CHIP CAP C 0.1U 50V K0603 X7R | R2_SA;HF_SA;G_SA; | MURATA;AVX;PHYCOMP;SAMSUNG;DARFON;WALSIN;YAGEO | GRM188R71H104KA93D;06035C104KAT2A;223858615649;CL10B104KB8NNNC;C1608X7R104KGT;0603B104K500CT;CC0603KRX7R9BB104 | Multiple |  | Purchase | SMT | 9 | PCS | C139 C148 C149 C150 C158 C160 C178 C207 C652 |
| 3 | B55.01107.M010 | 78.10521.2BL | CHIP CAP C 1U 16V K0603 X7R | R2_SA;HF_SA;G_SA; | KEMET;MURATA;TAIYO;TDK;YAGEO;WALSIN;SAMSUNG;DARFON | C0603C105K4RAC;GRM188R71C105KA12D;EMK107B7105KA-T;C1608X7R1C105KT;CC0603KRX7R7BB105;0603B105K160CT;CL10B105KO8NNNC;C1608X7R105KET | Multiple |  | Purchase | SMT | 48 | PCS | C100 C101 C102 C107 C108 C109 C110 C113 C114 C13 C144 C145 C147 C15 C156 C16 C161 C18 C182 C19 C197 C2 C202 C209 C21 C22 C229 C241 C26 C31 C54 C56 C58 C59 C60 C61 C62 C64 C645 C65 C87 C90 C92 C95 C97 C98 C99 C998 |
| 3 | B55.01107.M010 | 78.10522.2BL | CHIP CAP C 1U 25V K0603 X7R | R2_SA;HF_SA;G_SA; | MURATA;TAIYO;WALSIN;SAMSUNG;DARFON;YAGEO | GRM188R71E105KA12D;TMK107B7105KA-T;0603B105K250CT;CL10B105KA8NNNC;C1608X7R105KFT;CC0603KRX7R8BB105 | Multiple |  | Purchase | SMT | 1 | PCS | C128 |
| 3 | B55.01107.M010 | 78.10620.21L | CHIP CAP C 10U 6.3V K0805 X7R | R2_SA;HF_SA;G_SA; | MURATA;TAIYO;DARFON;KYOCERA | GRM21BR70J106KE76L;JMK212B7106KG-T;C2012X7R106KC;CM21X7R106K06AT | Multiple |  | Purchase | SMT | 38 | PCS | C172 C174 C187 C188 C191 C192 C193 C194 C199 C200 C215 C216 C217 C218 C223 C224 C225 C226 C231 C232 C235 C236 C237 C238 C243 C244 C57 C606 C610 C614 C617 C621 C625 C640 C643 C650 C655 C660 |
| 3 | B55.01107.M010 | 78.15322.2FL | CHIP CAP C 0.015U 25V K0402 X7R | R2_SA;HF_SA;G_SA; | MURATA;TDK;WALSIN;DARFON;PHYCOMP | GRM155R71E153KA61D;C1005X7R1E153KT000F;0402B153K250CT;C1005X7R153KFT;223891715638 | Multiple |  | Purchase | SMT | 1 | PCS | C133 |
| 3 | B55.01107.M010 | 78.18034.1FL | CHIP CAP C 18P 50V J0402 NP0 | R2_SA;HF_SA;G_SA; | WALSIN;AVX;TDK;PHYCOMP;TAIYO;DARFON;MURATA | 0402N180J500CT;04025A180JAT2A;C1005C0G1H180JT;223886915189;UMK105CH180JV-F;C1005NP0180JGT;GRM1555C1H180JA01D | Multiple |  | Purchase | SMT | 2 | PCS | C17 C20 |
| 3 | B55.01107.M010 | 78.22522.21L | CHIP CAP C 2.2U 25V K0805 X7R | R2_SA;HF_SA;G_SA; | WALSIN ; SAMSUNG ; PHYCOMP | 0805B225K250CT ; CL21B225KAFNNNE ; 222291015667 | Multiple |  | Purchase | SMT | 3 | PCS | C25 C28 C29 |
| 3 | B55.01107.M010 | 78.33034.1FL | CHIP CAP 33P 50V J0402 NPO(ROHS | R2_SA;HF_SA;G_SA; | AVX;DARFON;MURATA;PHYCOMP;SAMSUNG;TAIYO;MURATA;WALSIN;YAGEO | 04025A330JAT2A;C1005NP0330JGT;GRM1555C1H330JZ01D;223886915339;CL05C330JB5NNNC;UMK105CH330JV-F;GRM1555C1H330JA01D;0402N330J500CT;CC0402JRNPO9BN330 | Multiple |  | Purchase | SMT | 1 | PCS | C82 |
| 3 | B55.01107.M010 | 78.33224.2FL | CHIP CAP C 3300P 50V K0402 X7R | R2_SA;HF_SA;G_SA; | MURATA;AVX;TAIYO;PHYCOMP;DARFON;WALSIN;YAGEO | GRM155R71H332KA01D;04025C332KAT2A;UMK105B7332KV-F;223858715629;C1005X7R332KGT;0402B332K500CT;CC0402KRX7R9BB332 | Multiple |  | Purchase | SMT | 1 | PCS | C208 |
| 3 | B55.01107.M010 | 78.33324.2BL | CHIP CAP 0.033U 50V K0603 X7R | R2_SA;HF_SA;G_SA; | MURATA;AVX;PHYCOMP;DARFON;YAGEO | GRM188R71H333KA61D;06035C333KAT2A;223858615643;C1608X7R333KGT;CC0603KRX7R9BB333 | Multiple |  | Purchase | SMT | 1 | PCS | C146 |
| 3 | B55.01107.M010 | 78.47124.2FL | CHIP CAP C 470P  50V K0402 X7R | R2_SA;HF_SA;G_SA; | AVX;DARFON;MURATA;PHYCOMP;TAIYO;SAMSUNG;WALSIN;YAGEO | 04025C471KAT2A;C1005X7R471KGT;GRM155R71H471KA01D;223858715618;UMK105B7471KV-F;CL05B471KB5NNNC;0402B471K500CT;CC0402KRX7R9BB471 | Multiple |  | Purchase | SMT | 4 | PCS | C196 C228 C240 C644 |
| 3 | B55.01107.M010 | 78.47422.2BL | CHIP CAP C 0.47U 25V K0603 X7R | R2_SA;HF_SA;G_SA; | MURATA;SAMSUNG;DARFON | GRM188R71E474KA12D;CL10B474KA8NNNC;C1608X7R474KFT | Multiple |  | Purchase | SMT | 1 | PCS | C219 |
| 3 | B55.01107.M010 | 79.10710.2AL | CHIP CAP EL 100U 6.3V M7343 ESR17 | R2_SA;HF_SA; | PANASONIC | EEJRX0J101R | Single |  | Purchase | SMT | 2 | PCS | C657 C658 |
| 3 | B55.01107.M010 | 82.20043.221 | OSC 50MHZ 15P50PPM HXO-SC SMD | R2_SA;HF_SA; | HOSONIC | DSCB50.0000MTS | Multiple |  | Purchase | SMT | 1 | PCS | X2 |
| A | B55.01107.M010 | 82.20043.191 | OSC 50MHZ 50PPM 3.3V HSO321S | R2_SA;HF_SA; | HARMONY | SSW050000I3CH-S |  |  | Purchase |  |  |  |  |
| 3 | B55.01107.M010 | 82.30004.901 | XTAL 24MHZ 12PF20PPM HCX-3SB SMD | R2_SA;HF_SA; | HOSONIC | E3SB24.0000F12M22 | Multiple |  | Purchase | SMT | 1 | PCS | X1 |
| A | B55.01107.M010 | 82.30004.771 | XTAL 24MHZ 12P 30PPM HSX321S SMD | R2_SA;HF_SA; | HARMONY | X3S024000FC1H-HV |  |  | Purchase |  |  |  |  |
| 3 | B55.01107.M010 | 83.0005V.MAF | DIODE ESD PESD5V0F1BL,315 SOD882 | R2_SA;HF_SA; | NXP | PESD5V0F1BL,315 | Single |  | Purchase | SMT | 2 | PCS | D18 D19 |
| 3 | B55.01107.M010 | 83.01921.S70 | LED YEL GRN 19-21/G6C-BM2P1B/3T SMD | R2_SA;HF_SA;G_SA; | EVERLIGHT | 19-21/G6C-BM2P1B/3T | Multiple |  | Purchase | SMT | 1 | PCS | LED6 |
| A | B55.01107.M010 | 83.00191.I70 | LED GREEN LTST-C191KGKT SMD | R2_SA;HF_SA;G_SA; | LITEON | LTST-C191KGKT |  |  | Purchase |  |  |  |  |
| 3 | B55.01107.M010 | 83.R2003.K8F | DIODE S.B BAT54WS-7-F SOD-323 | R2_SA;HF_SA; | DIODES | BAT54WS-7-F | Multiple |  | Purchase | SMT | 1 | PCS | D11 |
| A | B55.01107.M010 | 083.00054.0A8F | DIODE S.B LBAT54HT1G SOD-323 | R2_SA;HF_SA; | LRC | LBAT54HT1G |  |  | Purchase |  |  |  |  |
| A | B55.01107.M010 | 83.2R004.A8F | DIODE S.B SD103AWS SOD-323 | R2_SA;HF_SA; | YEASHIN | SD103AWS |  |  | Purchase |  |  |  |  |
| 3 | B55.01107.M010 | 83.SMF15.0AH | DIODE TVS SMF15A SOD-123FL | R2_SA;HF_SA; | PANJIT | SMF15A | Multiple |  | Purchase | SMT | 1 | PCS | D1 |
| A | B55.01107.M010 | 83.00015.0AF | DIODE TVS DFLT15A-7 POWERDI123 | R2_SA;HF_SA; | DIODES | DFLT15A-7 |  |  | Purchase |  |  |  |  |
| 3 | B55.01107.M010 | 84.03904.T11 | XTOR MMBT3904 NPN SOT-23 | R2_SA;HF_SA;G_SA; | PANJIT | MMBT3904 | Multiple |  | Purchase | SMT | 3 | PCS | PQ1 Q2 Q3 |
| A | B55.01107.M010 | 84.03904.L06 | XTOR PMBS3904,215 NPN SOT23 (GP) | R2_SA;HF_SA;G_SA; | NEXPERIA | PMBS3904,215 |  |  | Purchase |  |  |  |  |
| A | B55.01107.M010 | 84.T3904.H11 | XTOR LMBT3904LT1G NPN SOT-23 | R2_SA;HF_SA;G_SA; | LRC | LMBT3904LT1G |  |  | Purchase |  |  |  |  |
| 3 | B55.01107.M010 | 84.08878.A37 | FET MOS FDS8878_G NC SO-8(HF) | R2_SA;HF_SA; | FAIRCHILD | FDS8878_G | Multiple |  | Purchase | SMT | 1 | PCS | PQ3 |
| A | B55.01107.M010 | 84.04172.037 | FET MOS SI4172DY-T1-GE3 NC SO8 | R2_SA;HF_SA; | VISHAY | SI4172DY-T1-GE3 |  |  | Purchase |  |  |  |  |
| 3 | B55.01107.M010 | 84.2N702.031 | FET MOS 2N7002K-7 NC SOT-23 2KV 300MA | R2_SA;HF_SA; | DIODES | 2N7002K-7 | Multiple |  | Purchase | SMT | 10 | PCS | PQ2 Q11 Q12 Q20 Q21 Q24 Q25 Q26 Q28 Q4 |
| A | B55.01107.M010 | 84.2N702.J31 | FET MOS 2N7002K NC SOT-23 ESD 2KV 300MA | R2_SA;HF_SA;G_SA; | PANJIT | 2N7002K |  |  | Purchase |  |  |  |  |
| 3 | B55.01107.M010 | B48.01133.0021 | PCB 16342-2 BRYCE CANYON IOM (M.2)8L GCE | R2_SA;HF_SA; | GCE | B48.01133.0021 | Multiple |  | Purchase | SMT | 1 | PCS | PCBL |
| A | B55.01107.M010 | B48.01149.0021 | PCB 16342-2 BRYCE CANYON IOM (M.2)8L TRI | R2_SA;HF_SA; | TRIPOD | B48.01149.0021 |  |  | Purchase |  |  |  |  |
| 2 | B55.01107.0010 | B60.0110V.0011 | ASSY NIC CARD LATCH BC MP | R2_SA;HF_SA; | FIVETECH | B60.0110V.0011 | Single | M | Purchase | DIP | 2 | PCS |  |
| 2 | B55.01107.0010 | BZA.01101.0055 | BRYCE CANYON NEW BMC F/W MODULE2 | R2; |  |  |  | M | Manufacture | DIP | 1 | PCS | FW |
| 3 | BZA.01101.0055 | 72.25635.A01 | IC FEROM MX25L25635FMI-10G SOP 16P | R2_SA;HF_SA; | MXIC | MX25L25635FMI-10G | Single |  | Purchase |  | 2 | PCS | U11 U29 |
| 3 | BZA.01101.0055 | B53.01101.00C1 | F/W BMC BRYCECANYON WBM_1.4.0 | R2; | TBD |  | Single |  | Manufacture |  | 1 | PCS |  |
